# Stackup_F0T_PDB_GPU_10L_2p36mm_IT-170GT_RTF_Rev0p2_20211201.xls — Information (pcb-stackup)
| Stackup Information : |  |  |  |
| Stackup Type |  |  | Single Material |
| Project Name |  |  | F0T |
| Board Class |  |  | PDB_GPU |
| Number of Layers |  |  | 10 |
| PCB Material |  |  | IT-170GT |
| Copper Foil |  |  | RTF (Roughness < 4um) |
| PCB Thickness (mm) |  |  | 2.36 |
| PCB Thickness (mil) |  |  | 92.9 |
| Aspect Ratio |  |  | 9.48 |
| Last Update |  |  | 44531 |
| Revision |  |  | 0.2 |
| Creator |  |  | Allen |
| Loss Requirement Table : |  |  |  |
| SDD21 @ Freq(GHz) |  |  |  |
| Requirement (db/inch) | Layer |  |  |
|  | Loss |  |  |
| Stackup History : |  |  |  |
| Date (yyyy/mm/dd) | Revision | Notes |  |
| 44490 | 0.1 | First release |  |
| 44531 | 0.2 | Update material from EM-370(Z) to IT-170(GT) |  |
